# T6G (Grand Teton) — schematic parts with pin connectivity, parts 8082–8082 of 8303; source: Cadence DE-HDL packaged netlist (pstxprt.dat, pstxnet.dat, pstchip.dat)

U26  GENOA_SP5  SOCKET6096_13568-001 IO  pkg SOCKET6096_93-4X120-45XA  page 37  (pins 1681-2016 of 6096)
  BC58  VSS_BC58  POWER  = GND
  BC59  MDA_PAR  OUT  = M_D_CPU1_SA_PAR
  BC60  MD0_CLK_H  OUT  = M_D_CPU1_CLK_DP<0>
  BC61  VSS_BC61  POWER  = GND
  BC62  MBA_PAR  OUT  = M_B_CPU1_SA_PAR
  BC63  VSS_BC63  POWER  = GND
  BC64  MB0_CLK_H  OUT  = M_B_CPU1_CLK_DP<0>
  BC65  VSS_BC65  POWER  = GND
  BC66  MFA_PAR  OUT  = M_F_CPU1_SA_PAR
  BC67  MF0_CLK_H  OUT  = M_F_CPU1_CLK_DP<0>
  BC68  VSS_BC68  POWER  = GND
  BC69  MEA_PAR  OUT  = M_E_CPU1_SA_PAR
  BC70  VSS_BC70  POWER  = GND
  BC71  ME0_CLK_H  OUT  = M_E_CPU1_CLK_DP<0>
  BC72  VSS_BC72  POWER  = GND
  BC73  MAA_PAR  OUT  = M_A_CPU1_SA_PAR
  BC74  MA0_CLK_H  OUT  = M_A_CPU1_CLK_DP<0>
  BC75  VSS_BC75  POWER  = GND
  BD2  MG0_CLK_L  OUT  = M_G_CPU1_CLK_DN<0>
  BD3  VSS_BD3  POWER  = GND
  BD4  RSVD_BD4  TRI  = NC
  BD5  VDDCR_SOC_BD5  POWER  = PVDDCR_SOC_P1
  BD6  MK0_CLK_L  OUT  = M_K_CPU1_CLK_DN<0>
  BD7  RSVD_BD7  TRI  = NC
  BD8  VSS_BD8  POWER  = GND
  BD9  ML0_CLK_L  OUT  = M_L_CPU1_CLK_DN<0>
  BD10  VSS_BD10  POWER  = GND
  BD11  RSVD_BD11  TRI  = NC
  BD12  VDDCR_SOC_BD12  POWER  = PVDDCR_SOC_P1
  BD13  MH0_CLK_L  OUT  = M_H_CPU1_CLK_DN<0>
  BD14  RSVD_BD14  TRI  = NC
  BD15  VSS_BD15  POWER  = GND
  BD16  MJ0_CLK_L  OUT  = M_J_CPU1_CLK_DN<0>
  BD17  VSS_BD17  POWER  = GND
  BD18  RSVD_BD18  TRI  = NC
  BD19  VDDCR_SOC_BD19  POWER  = PVDDCR_SOC_P1
  BD20  MI0_CLK_L  OUT  = M_I_CPU1_CLK_DN<0>
  BD21  RSVD_BD21  TRI  = NC
  BD22  VDDCR_SOC_BD22  POWER  = PVDDCR_SOC_P1
  BD23  VSS_BD23  POWER  = GND
  BD24  VDDCR_SOC_BD24  POWER  = PVDDCR_SOC_P1
  BD25  VSS_BD25  POWER  = GND
  BD26  VDDCR_SOC_BD26  POWER  = PVDDCR_SOC_P1
  BD27  VSS_BD27  POWER  = GND
  BD28  VDDCR_SOC_BD28  POWER  = PVDDCR_SOC_P1
  BD48  VDDCR_SOC_BD48  POWER  = PVDDCR_SOC_P1
  BD49  VSS_BD49  POWER  = GND
  BD50  VDDIO_BD50  POWER  = PVDDIO_P1
  BD51  VSS_BD51  POWER  = GND
  BD52  VDDIO_BD52  POWER  = PVDDIO_P1
  BD53  VSS_BD53  POWER  = GND
  BD54  VDDIO_BD54  POWER  = PVDDIO_P1
  BD55  RSVD_BD55  TRI  = NC
  BD56  MC0_CLK_L  OUT  = M_C_CPU1_CLK_DN<0>
  BD57  VSS_BD57  POWER  = GND
  BD58  RSVD_BD58  TRI  = NC
  BD59  VSS_BD59  POWER  = GND
  BD60  MD0_CLK_L  OUT  = M_D_CPU1_CLK_DN<0>
  BD61  VSS_BD61  POWER  = GND
  BD62  RSVD_BD62  TRI  = NC
  BD63  MB0_CLK_L  OUT  = M_B_CPU1_CLK_DN<0>
  BD64  VSS_BD64  POWER  = GND
  BD65  RSVD_BD65  TRI  = NC
  BD66  VSS_BD66  POWER  = GND
  BD67  MF0_CLK_L  OUT  = M_F_CPU1_CLK_DN<0>
  BD68  VSS_BD68  POWER  = GND
  BD69  RSVD_BD69  TRI  = NC
  BD70  ME0_CLK_L  OUT  = M_E_CPU1_CLK_DN<0>
  BD71  VSS_BD71  POWER  = GND
  BD72  RSVD_BD72  TRI  = NC
  BD73  VSS_BD73  POWER  = GND
  BD74  MA0_CLK_L  OUT  = M_A_CPU1_CLK_DN<0>
  BF2  MG1_CLK_H  OUT  = NC
  BF3  VSS_BF3  POWER  = GND
  BF4  TEST39G  OUT  = TP_M_G_CPU1_SA_TEST39G
  BF5  VSS_BF5  POWER  = GND
  BF6  MK1_CLK_H  OUT  = NC
  BF7  TEST39K  OUT  = TP_M_K_CPU1_SA_TEST39K
  BF8  VSS_BF8  POWER  = GND
  BF9  ML1_CLK_H  OUT  = NC
  BF10  VSS_BF10  POWER  = GND
  BF11  TEST39L  OUT  = TP_M_L_CPU1_SA_TEST39L
  BF12  VSS_BF12  POWER  = GND
  BF13  MH1_CLK_H  OUT  = NC
  BF14  TEST39H  OUT  = TP_M_H_CPU1_SA_TEST39H
  BF15  VSS_BF15  POWER  = GND
  BF16  MJ1_CLK_H  OUT  = NC
  BF17  VSS_BF17  POWER  = GND
  BF18  TEST39J  OUT  = TP_M_J_CPU1_SA_TEST39J
  BF19  VSS_BF19  POWER  = GND
  BF20  MI1_CLK_H  OUT  = NC
  BF21  TEST39I  OUT  = TP_M_I_CPU1_SA_TEST39I
  BF22  VSS_BF22  POWER  = GND
  BF23  VDDCR_SOC_BF23  POWER  = PVDDCR_SOC_P1
  BF24  VSS_BF24  POWER  = GND
  BF25  VDDCR_SOC_BF25  POWER  = PVDDCR_SOC_P1
  BF26  VSS_BF26  POWER  = GND
  BF27  VDDCR_SOC_BF27  POWER  = PVDDCR_SOC_P1
  BF28  VSS_BF28  POWER  = GND
  BF48  VDDCR_SOC_BF48  POWER  = PVDDCR_SOC_P1
  BF49  VSS_BF49  POWER  = GND
  BF50  VSS_BF50  POWER  = GND
  BF51  VDDIO_BF51  POWER  = PVDDIO_P1
  BF52  VSS_BF52  POWER  = GND
  BF53  VDDIO_BF53  POWER  = PVDDIO_P1
  BF54  VSS_BF54  POWER  = GND
  BF55  TEST39C  OUT  = TP_M_C_CPU1_SA_TEST39C
  BF56  MC1_CLK_H  OUT  = NC
  BF57  VDDIO_BF57  POWER  = PVDDIO_P1
  BF58  TEST39D  OUT  = TP_M_D_CPU1_SA_TEST39D
  BF59  VSS_BF59  POWER  = GND
  BF60  MD1_CLK_H  OUT  = NC
  BF61  VSS_BF61  POWER  = GND
  BF62  TEST39B  OUT  = TP_M_B_CPU1_SA_TEST39B
  BF63  MB1_CLK_H  OUT  = NC
  BF64  VDDIO_BF64  POWER  = PVDDIO_P1
  BF65  TEST39F  OUT  = TP_M_F_CPU1_SA_TEST39F
  BF66  VSS_BF66  POWER  = GND
  BF67  MF1_CLK_H  OUT  = NC
  BF68  VSS_BF68  POWER  = GND
  BF69  TEST39E  OUT  = TP_M_E_CPU1_SA_TEST39E
  BF70  ME1_CLK_H  OUT  = NC
  BF71  VDDIO_BF71  POWER  = PVDDIO_P1
  BF72  TEST39A  OUT  = TP_M_A_CPU1_SA_TEST39A
  BF73  VSS_BF73  POWER  = GND
  BF74  MA1_CLK_H  OUT  = NC
  BG1  VSS_BG1  POWER  = GND
  BG2  MG1_CLK_L  OUT  = NC
  BG3  MGB_CA0  OUT  = M_G_CPU1_SB_CA<0>
  BG4  VSS_BG4  POWER  = GND
  BG5  MK1_CLK_L  OUT  = NC
  BG6  VSS_BG6  POWER  = GND
  BG7  MKB_CA0  OUT  = M_K_CPU1_SB_CA<0>
  BG8  VSS_BG8  POWER  = GND
  BG9  ML1_CLK_L  OUT  = NC
  BG10  MLB_CA0  OUT  = M_L_CPU1_SB_CA<0>
  BG11  VSS_BG11  POWER  = GND
  BG12  MH1_CLK_L  OUT  = NC
  BG13  VSS_BG13  POWER  = GND
  BG14  MHB_CA0  OUT  = M_H_CPU1_SB_CA<0>
  BG15  VSS_BG15  POWER  = GND
  BG16  MJ1_CLK_L  OUT  = NC
  BG17  MJB_CA0  OUT  = M_J_CPU1_SB_CA<0>
  BG18  VSS_BG18  POWER  = GND
  BG19  MI1_CLK_L  OUT  = NC
  BG20  VSS_BG20  POWER  = GND
  BG21  MIB_CA0  OUT  = M_I_CPU1_SB_CA<0>
  BG22  VDDCR_SOC_BG22  POWER  = PVDDCR_SOC_P1
  BG23  VSS_BG23  POWER  = GND
  BG24  VDDCR_SOC_BG24  POWER  = PVDDCR_SOC_P1
  BG25  VSS_BG25  POWER  = GND
  BG26  VDDCR_SOC_BG26  POWER  = PVDDCR_SOC_P1
  BG27  VSS_BG27  POWER  = GND
  BG28  VDDCR_SOC_BG28  POWER  = PVDDCR_SOC_P1
  BG48  VDDCR_SOC_BG48  POWER  = PVDDCR_SOC_P1
  BG49  VSS_BG49  POWER  = GND
  BG50  VDDIO_BG50  POWER  = PVDDIO_P1
  BG51  VSS_BG51  POWER  = GND
  BG52  VDDIO_BG52  POWER  = PVDDIO_P1
  BG53  VSS_BG53  POWER  = GND
  BG54  VDDIO_BG54  POWER  = PVDDIO_P1
  BG55  MCB_CA0  OUT  = M_C_CPU1_SB_CA<0>
  BG56  VSS_BG56  POWER  = GND
  BG57  MC1_CLK_L  OUT  = NC
  BG58  VSS_BG58  POWER  = GND
  BG59  MDB_CA0  OUT  = M_D_CPU1_SB_CA<0>
  BG60  MD1_CLK_L  OUT  = NC
  BG61  VSS_BG61  POWER  = GND
  BG62  MBB_CA0  OUT  = M_B_CPU1_SB_CA<0>
  BG63  VSS_BG63  POWER  = GND
  BG64  MB1_CLK_L  OUT  = NC
  BG65  VSS_BG65  POWER  = GND
  BG66  MFB_CA0  OUT  = M_F_CPU1_SB_CA<0>
  BG67  MF1_CLK_L  OUT  = NC
  BG68  VSS_BG68  POWER  = GND
  BG69  MEB_CA0  OUT  = M_E_CPU1_SB_CA<0>
  BG70  VSS_BG70  POWER  = GND
  BG71  ME1_CLK_L  OUT  = NC
  BG72  VSS_BG72  POWER  = GND
  BG73  MAB_CA0  OUT  = M_A_CPU1_SB_CA<0>
  BG74  MA1_CLK_L  OUT  = NC
  BG75  VSS_BG75  POWER  = GND
  BH2  MGB_CA2  OUT  = M_G_CPU1_SB_CA<2>
  BH3  VSS_BH3  POWER  = GND
  BH4  MGB_CA1  OUT  = M_G_CPU1_SB_CA<1>
  BH5  VSS_BH5  POWER  = GND
  BH6  MKB_CA2  OUT  = M_K_CPU1_SB_CA<2>
  BH7  MKB_CA1  OUT  = M_K_CPU1_SB_CA<1>
  BH8  VSS_BH8  POWER  = GND
  BH9  MLB_CA2  OUT  = M_L_CPU1_SB_CA<2>
  BH10  VSS_BH10  POWER  = GND
  BH11  MLB_CA1  OUT  = M_L_CPU1_SB_CA<1>
  BH12  VSS_BH12  POWER  = GND
  BH13  MHB_CA2  OUT  = M_H_CPU1_SB_CA<2>
  BH14  MHB_CA1  OUT  = M_H_CPU1_SB_CA<1>
  BH15  VSS_BH15  POWER  = GND
  BH16  MJB_CA2  OUT  = M_J_CPU1_SB_CA<2>
  BH17  VSS_BH17  POWER  = GND
  BH18  MJB_CA1  OUT  = M_J_CPU1_SB_CA<1>
  BH19  VSS_BH19  POWER  = GND
  BH20  MIB_CA2  OUT  = M_I_CPU1_SB_CA<2>
  BH21  MIB_CA1  OUT  = M_I_CPU1_SB_CA<1>
  BH22  VSS_BH22  POWER  = GND
  BH23  VDDCR_SOC_BH23  POWER  = PVDDCR_SOC_P1
  BH24  VSS_BH24  POWER  = GND
  BH25  VDDCR_SOC_BH25  POWER  = PVDDCR_SOC_P1
  BH26  VSS_BH26  POWER  = GND
  BH27  VDDIO_AUDIO  POWER  = PVDD18_S5_P1
  BH28  VSS_BH28  POWER  = GND
  BH48  VDDCR_SOC_BH48  POWER  = PVDDCR_SOC_P1
  BH49  VSS_BH49  POWER  = GND
  BH50  VSS_BH50  POWER  = GND
  BH51  VDDIO_BH51  POWER  = PVDDIO_P1
  BH52  VSS_BH52  POWER  = GND
  BH53  VDDIO_BH53  POWER  = PVDDIO_P1
  BH54  VSS_BH54  POWER  = GND
  BH55  MCB_CA1  OUT  = M_C_CPU1_SB_CA<1>
  BH56  MCB_CA2  OUT  = M_C_CPU1_SB_CA<2>
  BH57  VSS_BH57  POWER  = GND
  BH58  MDB_CA1  OUT  = M_D_CPU1_SB_CA<1>
  BH59  VSS_BH59  POWER  = GND
  BH60  MDB_CA2  OUT  = M_D_CPU1_SB_CA<2>
  BH61  VSS_BH61  POWER  = GND
  BH62  MBB_CA1  OUT  = M_B_CPU1_SB_CA<1>
  BH63  MBB_CA2  OUT  = M_B_CPU1_SB_CA<2>
  BH64  VSS_BH64  POWER  = GND
  BH65  MFB_CA1  OUT  = M_F_CPU1_SB_CA<1>
  BH66  VSS_BH66  POWER  = GND
  BH67  MFB_CA2  OUT  = M_F_CPU1_SB_CA<2>
  BH68  VSS_BH68  POWER  = GND
  BH69  MEB_CA1  OUT  = M_E_CPU1_SB_CA<1>
  BH70  MEB_CA2  OUT  = M_E_CPU1_SB_CA<2>
  BH71  VSS_BH71  POWER  = GND
  BH72  MAB_CA1  OUT  = M_A_CPU1_SB_CA<1>
  BH73  VSS_BH73  POWER  = GND
  BH74  MAB_CA2  OUT  = M_A_CPU1_SB_CA<2>
  BJ1  VSS_BJ1  POWER  = GND
  BJ2  MGB_CA3  OUT  = M_G_CPU1_SB_CA<3>
  BJ3  MGB_CA4  OUT  = M_G_CPU1_SB_CA<4>
  BJ4  VDDCR_SOC_BJ4  POWER  = PVDDCR_SOC_P1
  BJ5  MKB_CA3  OUT  = M_K_CPU1_SB_CA<3>
  BJ6  VSS_BJ6  POWER  = GND
  BJ7  MKB_CA4  OUT  = M_K_CPU1_SB_CA<4>
  BJ8  VSS_BJ8  POWER  = GND
  BJ9  MLB_CA3  OUT  = M_L_CPU1_SB_CA<3>
  BJ10  MLB_CA4  OUT  = M_L_CPU1_SB_CA<4>
  BJ11  VDDCR_SOC_BJ11  POWER  = PVDDCR_SOC_P1
  BJ12  MHB_CA3  OUT  = M_H_CPU1_SB_CA<3>
  BJ13  VSS_BJ13  POWER  = GND
  BJ14  MHB_CA4  OUT  = M_H_CPU1_SB_CA<4>
  BJ15  VSS_BJ15  POWER  = GND
  BJ16  MJB_CA3  OUT  = M_J_CPU1_SB_CA<3>
  BJ17  MJB_CA4  OUT  = M_J_CPU1_SB_CA<4>
  BJ18  VDD_11_S3_BJ18  POWER  = PVDD11_S3_P1
  BJ19  MIB_CA3  OUT  = M_I_CPU1_SB_CA<3>
  BJ20  VSS_BJ20  POWER  = GND
  BJ21  MIB_CA4  OUT  = M_I_CPU1_SB_CA<4>
  BJ22  VSS_BJ22  POWER  = GND
  BJ23  VDD_11_S3_BJ23  POWER  = PVDD11_S3_P1
  BJ24  VSS_BJ24  POWER  = GND
  BJ25  VDD_11_S3_BJ25  POWER  = PVDD11_S3_P1
  BJ26  VSS_BJ26  POWER  = GND
  BJ27  VDD_11_S3_BJ27  POWER  = PVDD11_S3_P1
  BJ28  VSS_BJ28  POWER  = GND
  BJ48  VDDCR_SOC_BJ48  POWER  = PVDDCR_SOC_P1
  BJ49  VSS_BJ49  POWER  = GND
  BJ50  VDDIO_BJ50  POWER  = PVDDIO_P1
  BJ51  VSS_BJ51  POWER  = GND
  BJ52  VDDIO_BJ52  POWER  = PVDDIO_P1
  BJ53  VSS_BJ53  POWER  = GND
  BJ54  VDDIO_BJ54  POWER  = PVDDIO_P1
  BJ55  MCB_CA4  OUT  = M_C_CPU1_SB_CA<4>
  BJ56  VSS_BJ56  POWER  = GND
  BJ57  MCB_CA3  OUT  = M_C_CPU1_SB_CA<3>
  BJ58  VDDIO_BJ58  POWER  = PVDDIO_P1
  BJ59  MDB_CA4  OUT  = M_D_CPU1_SB_CA<4>
  BJ60  MDB_CA3  OUT  = M_D_CPU1_SB_CA<3>
  BJ61  VSS_BJ61  POWER  = GND
  BJ62  MBB_CA4  OUT  = M_B_CPU1_SB_CA<4>
  BJ63  VSS_BJ63  POWER  = GND
  BJ64  MBB_CA3  OUT  = M_B_CPU1_SB_CA<3>
  BJ65  VDDIO_BJ65  POWER  = PVDDIO_P1
  BJ66  MFB_CA4  OUT  = M_F_CPU1_SB_CA<4>
  BJ67  MFB_CA3  OUT  = M_F_CPU1_SB_CA<3>
  BJ68  VSS_BJ68  POWER  = GND
  BJ69  MEB_CA4  OUT  = M_E_CPU1_SB_CA<4>
  BJ70  VSS_BJ70  POWER  = GND
  BJ71  MEB_CA3  OUT  = M_E_CPU1_SB_CA<3>
  BJ72  VDDIO_BJ72  POWER  = PVDDIO_P1
  BJ73  MAB_CA4  OUT  = M_A_CPU1_SB_CA<4>
  BJ74  MAB_CA3  OUT  = M_A_CPU1_SB_CA<3>
  BJ75  VSS_BJ75  POWER  = GND
  BK2  MGB_CA6  OUT  = M_G_CPU1_SB_CA<6>
  BK3  VSS_BK3  POWER  = GND
  BK4  MGB_CA5  OUT  = M_G_CPU1_SB_CA<5>
  BK5  VSS_BK5  POWER  = GND
  BK6  MKB_CA6  OUT  = M_K_CPU1_SB_CA<6>
  BK7  MKB_CA5  OUT  = M_K_CPU1_SB_CA<5>
  BK8  VSS_BK8  POWER  = GND
  BK9  MLB_CA6  OUT  = M_L_CPU1_SB_CA<6>
  BK10  VSS_BK10  POWER  = GND
  BK11  MLB_CA5  OUT  = M_L_CPU1_SB_CA<5>
  BK12  VSS_BK12  POWER  = GND
  BK13  MHB_CA6  OUT  = M_H_CPU1_SB_CA<6>
  BK14  MHB_CA5  OUT  = M_H_CPU1_SB_CA<5>
  BK15  VSS_BK15  POWER  = GND
  BK16  MJB_CA6  OUT  = M_J_CPU1_SB_CA<6>
  BK17  VSS_BK17  POWER  = GND
  BK18  MJB_CA5  OUT  = M_J_CPU1_SB_CA<5>
  BK19  VSS_BK19  POWER  = GND
  BK20  MIB_CA6  OUT  = M_I_CPU1_SB_CA<6>
  BK21  MIB_CA5  OUT  = M_I_CPU1_SB_CA<5>
  BK22  VDD_11_S3_BK22  POWER  = PVDD11_S3_P1
  BK23  VSS_BK23  POWER  = GND
  BK24  VDD_11_S3_BK24  POWER  = PVDD11_S3_P1
  BK25  VSS_BK25  POWER  = GND
  BK26  VDD_11_S3_BK26  POWER  = PVDD11_S3_P1
  BK27  VSS_BK27  POWER  = GND
  BK28  VDD_11_S3_BK28  POWER  = PVDD11_S3_P1
  BK48  VSS_BK48  POWER  = GND
  BK49  VDD_11_S3_BK49  POWER  = PVDD11_S3_P1
  BK50  VSS_BK50  POWER  = GND
  BK51  VDDIO_BK51  POWER  = PVDDIO_P1
  BK52  VSS_BK52  POWER  = GND
  BK53  VDDIO_BK53  POWER  = PVDDIO_P1
  BK54  VSS_BK54  POWER  = GND
  BK55  MCB_CA5  OUT  = M_C_CPU1_SB_CA<5>
  BK56  MCB_CA6  OUT  = M_C_CPU1_SB_CA<6>
  BK57  VSS_BK57  POWER  = GND
  BK58  MDB_CA5  OUT  = M_D_CPU1_SB_CA<5>
  BK59  VSS_BK59  POWER  = GND
  BK60  MDB_CA6  OUT  = M_D_CPU1_SB_CA<6>
  BK61  VSS_BK61  POWER  = GND
  BK62  MBB_CA5  OUT  = M_B_CPU1_SB_CA<5>
  BK63  MBB_CA6  OUT  = M_B_CPU1_SB_CA<6>
  BK64  VSS_BK64  POWER  = GND
